(kicad_pcb
	(version 20260206)
	(generator "pcbnew")
	(generator_version "10.0")
	(general
		(thickness 1.6)
		(legacy_teardrops no)
	)
	(paper "A4")
	(title_block
		(title "Bryce Canyon_F.DPB_16315-1-OCP.brd")
		(comment 1 "Bryce Canyon / footprints 566-569 of 2223")
	)
	(layers
		(0 "F.Cu" signal "TOP")
		(4 "In1.Cu" signal "L2GND")
		(6 "In2.Cu" signal "L3")
		(8 "In3.Cu" signal "L4GND")
		(10 "In4.Cu" signal "L5")
		(12 "In5.Cu" signal "L6VCC")
		(14 "In6.Cu" signal "L7VCC")
		(16 "In7.Cu" signal "L8")
		(18 "In8.Cu" signal "L9GND")
		(20 "In9.Cu" signal "L10")
		(22 "In10.Cu" signal "L11GND")
		(2 "B.Cu" signal "BOTTOM")
		(9 "F.Adhes" user "F.Adhesive")
		(11 "B.Adhes" user "B.Adhesive")
		(13 "F.Paste" user "Package Geometry/Pastemask Top")
		(15 "B.Paste" user "Package Geometry/Pastemask Bottom")
		(5 "F.SilkS" user "Ref Des/Silkscreen Top")
		(7 "B.SilkS" user "Ref Des/Silkscreen Bottom")
		(1 "F.Mask" user "Board Geometry/Soldermask Top")
		(3 "B.Mask" user "Board Geometry/Soldermask Bottom")
		(17 "Dwgs.User" user "User.Drawings")
		(19 "Cmts.User" user "User.Comments")
		(21 "Eco1.User" user "User.Eco1")
		(23 "Eco2.User" user "User.Eco2")
		(25 "Edge.Cuts" user "Board Geometry/Outline")
		(27 "Margin" user)
		(31 "F.CrtYd" user "Package Geometry/Place Bound Top")
		(29 "B.CrtYd" user "Package Geometry/Place Bound Bottom")
		(35 "F.Fab" user "Ref Des/Assembly Top")
		(33 "B.Fab" user "Ref Des/Assembly Bottom")
	)
	(footprint ""
		(layer "F.Cu")
		(at 55.282846 -292.270942)
		(property "Reference" "R152"
			(at 0 0 0)
			(layer "F.SilkS")
			(hide yes)
			(effects
				(font
					(size 1.27 1.27)
				)
			)
		)
		(property "Value" "2R6F-GP"
			(at -0.0508 -4.8514 0)
			(unlocked yes)
			(layer "F.Fab")
			(hide yes)
			(effects
				(font
					(size 1.016 1.016)
					(thickness 0.1524)
				)
			)
		)
		(property "Device Type" "R1206H26"
			(at 0 -6.3754 0)
			(unlocked yes)
			(layer "F.Fab")
			(hide yes)
			(effects
				(font
					(size 1.016 1.016)
					(thickness 0.1524)
				)
			)
		)
		(duplicate_pad_numbers_are_jumpers no)
		(fp_line
			(start -1.016 -2.2352)
			(end 1.016 -2.2352)
			(stroke
				(width 0.1524)
				(type default)
			)
			(layer "F.SilkS")
		)
		(fp_line
			(start -1.016 2.2352)
			(end -1.016 -2.2352)
			(stroke
				(width 0.1524)
				(type default)
			)
			(layer "F.SilkS")
		)
		(fp_line
			(start 1.016 -2.2352)
			(end 1.016 2.2352)
			(stroke
				(width 0.1524)
				(type default)
			)
			(layer "F.SilkS")
		)
		(fp_line
			(start 1.016 2.2352)
			(end -1.016 2.2352)
			(stroke
				(width 0.1524)
				(type default)
			)
			(layer "F.SilkS")
		)
		(fp_rect
			(start -1.0922 2.3114)
			(end 1.0922 -2.3114)
			(stroke
				(width 0)
				(type default)
			)
			(fill no)
			(layer "F.CrtYd")
		)
		(fp_poly
			(pts
				(xy -1.0922 -2.3114) (xy 1.0922 -2.3114) (xy 1.0922 2.3114) (xy -1.0922 2.3114)
			)
			(stroke
				(width 0)
				(type default)
			)
			(fill no)
			(layer "F.Fab")
		)
		(pad "1" smd rect
			(at 0 -1.397)
			(size 1.651 1.27)
			(layers "F.Cu" "F.Mask" "F.Paste")
			(net "P5V_HDD1")
		)
		(pad "2" smd rect
			(at 0 1.397)
			(size 1.651 1.27)
			(layers "F.Cu" "F.Mask" "F.Paste")
			(net "5V_PRE_1")
		)
	)
	(footprint ""
		(layer "F.Cu")
		(at 16.824198 -168.152318 -90)
		(property "Reference" "C204"
			(at 0 0 270)
			(layer "F.SilkS")
			(hide yes)
			(effects
				(font
					(size 1.27 1.27)
				)
			)
		)
		(property "Value" "SCD033U25V2KX-GP"
			(at 1.1811 -2.7051 270)
			(unlocked yes)
			(layer "F.Fab")
			(hide yes)
			(effects
				(font
					(size 1.016 1.016)
					(thickness 0.1524)
				)
			)
		)
		(property "Device Type" "C402H22"
			(at 1.1811 -4.2291 270)
			(unlocked yes)
			(layer "F.Fab")
			(hide yes)
			(effects
				(font
					(size 1.016 1.016)
					(thickness 0.1524)
				)
			)
		)
		(duplicate_pad_numbers_are_jumpers no)
		(fp_rect
			(start -0.4318 0.9525)
			(end 0.4318 -0.9525)
			(stroke
				(width 0)
				(type default)
			)
			(fill no)
			(layer "F.CrtYd")
		)
		(fp_rect
			(start -0.4318 0.9525)
			(end 0.4318 -0.9525)
			(stroke
				(width 0)
				(type default)
			)
			(fill no)
			(layer "F.Fab")
		)
		(pad "1" smd custom
			(at 0 -0.4445 270)
			(size 0.1524 0.1524)
			(layers "F.Cu" "F.Mask" "F.Paste")
			(net "SW_HDD_P12")
			(options
				(clearance outline)
				(anchor circle)
			)
			(primitives
				(gr_poly
					(pts
						(arc
							(start 0.3048 -0.2032)
							(mid 0.275042 -0.275042)
							(end 0.2032 -0.3048)
						)
						(arc
							(start -0.2032 -0.3048)
							(mid -0.275042 -0.275042)
							(end -0.3048 -0.2032)
						)
						(arc
							(start -0.3048 0.2032)
							(mid -0.275042 0.275042)
							(end -0.2032 0.3048)
						)
						(arc
							(start 0.2032 0.3048)
							(mid 0.275042 0.275042)
							(end 0.3048 0.2032)
						)
					)
					(width 0)
					(fill yes)
				)
			)
		)
		(pad "2" smd custom
			(at 0 0.4445 270)
			(size 0.1524 0.1524)
			(layers "F.Cu" "F.Mask" "F.Paste")
			(net "GND")
			(options
				(clearance outline)
				(anchor circle)
			)
			(primitives
				(gr_poly
					(pts
						(arc
							(start 0.3048 -0.2032)
							(mid 0.275042 -0.275042)
							(end 0.2032 -0.3048)
						)
						(arc
							(start -0.2032 -0.3048)
							(mid -0.275042 -0.275042)
							(end -0.3048 -0.2032)
						)
						(arc
							(start -0.3048 0.2032)
							(mid -0.275042 0.275042)
							(end -0.2032 0.3048)
						)
						(arc
							(start 0.2032 0.3048)
							(mid 0.275042 0.275042)
							(end 0.3048 0.2032)
						)
					)
					(width 0)
					(fill yes)
				)
			)
		)
	)
	(footprint ""
		(layer "F.Cu")
		(at 276.2758 11.8618)
		(property "Reference" "D44"
			(at 0 0 0)
			(layer "F.SilkS")
			(hide yes)
			(effects
				(font
					(size 1.27 1.27)
				)
			)
		)
		(property "Value" "MMPZ5228BPT-GP"
			(at 0 -6.7818 0)
			(unlocked yes)
			(layer "F.Fab")
			(hide yes)
			(effects
				(font
					(size 1.016 1.016)
					(thickness 0.1524)
				)
			)
		)
		(property "Device Type" "SOD323AKH40"
			(at 0 -8.6868 0)
			(unlocked yes)
			(layer "F.Fab")
			(hide yes)
			(effects
				(font
					(size 1.016 1.016)
					(thickness 0.1524)
				)
			)
		)
		(duplicate_pad_numbers_are_jumpers no)
		(fp_line
			(start -0.889 -1.9304)
			(end 0.889 -1.9304)
			(stroke
				(width 0.1524)
				(type default)
			)
			(layer "F.SilkS")
		)
		(fp_line
			(start -0.889 2.159)
			(end -0.889 -1.9304)
			(stroke
				(width 0.1524)
				(type default)
			)
			(layer "F.SilkS")
		)
		(fp_line
			(start 0.762 2.0574)
			(end -0.762 2.0574)
			(stroke
				(width 0.508)
				(type default)
			)
			(layer "F.SilkS")
		)
		(fp_line
			(start 0.889 -1.9304)
			(end 0.889 2.159)
			(stroke
				(width 0.1524)
				(type default)
			)
			(layer "F.SilkS")
		)
		(fp_line
			(start 0.889 2.159)
			(end -0.889 2.159)
			(stroke
				(width 0.1524)
				(type default)
			)
			(layer "F.SilkS")
		)
		(fp_rect
			(start -1.016 2.3114)
			(end 1.016 -2.0066)
			(stroke
				(width 0)
				(type default)
			)
			(fill no)
			(layer "F.CrtYd")
		)
		(fp_poly
			(pts
				(xy -1.016 -2.0066) (xy 1.016 -2.0066) (xy 1.016 2.3114) (xy -1.016 2.3114)
			)
			(stroke
				(width 0)
				(type default)
			)
			(fill no)
			(layer "F.Fab")
		)
		(pad "A" smd rect
			(at 0 -1.143)
			(size 0.5588 1.016)
			(layers "F.Cu" "F.Mask" "F.Paste")
			(net "GND")
		)
		(pad "K" smd rect
			(at 0 1.143)
			(size 0.5588 1.016)
			(layers "F.Cu" "F.Mask" "F.Paste")
			(net "VCCP")
		)
	)
	(footprint ""
		(layer "F.Cu")
		(at 325.550022 -57.909968 -90)
		(property "Reference" "HDDSAS30"
			(at 0 0 270)
			(layer "F.SilkS")
			(hide yes)
			(effects
				(font
					(size 1.27 1.27)
				)
			)
		)
		(property "Value" "SKT-SAS15P-14P-45-GP"
			(at -20.7645 -8.9789 270)
			(unlocked yes)
			(layer "F.Fab")
			(hide yes)
			(effects
				(font
					(size 1.016 1.016)
					(thickness 0.1524)
				)
			)
		)
		(property "Device Type" "10120818-001C-TRLF"
			(at -20.7645 -10.5029 270)
			(unlocked yes)
			(layer "F.Fab")
			(hide yes)
			(effects
				(font
					(size 1.016 1.016)
					(thickness 0.1524)
				)
			)
		)
		(duplicate_pad_numbers_are_jumpers no)
		(fp_line
			(start 1.651 4.2926)
			(end 1.651 3.0099)
			(stroke
				(width 0.1524)
				(type default)
			)
			(layer "F.SilkS")
		)
		(fp_line
			(start 8.509 4.2926)
			(end 1.651 4.2926)
			(stroke
				(width 0.1524)
				(type default)
			)
			(layer "F.SilkS")
		)
		(fp_line
			(start -23.4188 3.0099)
			(end -23.4188 -3.2512)
			(stroke
				(width 0.1524)
				(type default)
			)
			(layer "F.SilkS")
		)
		(fp_line
			(start 1.651 3.0099)
			(end -23.4188 3.0099)
			(stroke
				(width 0.1524)
				(type default)
			)
			(layer "F.SilkS")
		)
		(fp_line
			(start 8.509 3.0099)
			(end 8.509 4.2926)
			(stroke
				(width 0.1524)
				(type default)
			)
			(layer "F.SilkS")
		)
		(fp_line
			(start 23.4188 3.0099)
			(end 8.509 3.0099)
			(stroke
				(width 0.1524)
				(type default)
			)
			(layer "F.SilkS")
		)
		(fp_line
			(start -23.4188 -3.2512)
			(end 23.4188 -3.2512)
			(stroke
				(width 0.1524)
				(type default)
			)
			(layer "F.SilkS")
		)
		(fp_line
			(start 23.4188 -3.2512)
			(end 23.4188 3.0099)
			(stroke
				(width 0.1524)
				(type default)
			)
			(layer "F.SilkS")
		)
		(fp_line
			(start 15.5067 -3.3401)
			(end 16.2687 -3.3401)
			(stroke
				(width 0.3302)
				(type default)
			)
			(layer "F.SilkS")
		)
		(fp_poly
			(pts
				(xy 15.868904 -3.230372) (xy 16.503904 -3.865372) (xy 15.233904 -3.865372)
			)
			(stroke
				(width 0)
				(type default)
			)
			(fill yes)
			(layer "F.SilkS")
		)
		(fp_poly
			(pts
				(xy -22.8727 -2.7559) (xy 22.8727 -2.7559) (xy 22.8727 2.7559) (xy 8.255 2.7559) (xy 8.255 3.5179)
				(xy 1.905 3.5179) (xy 1.905 2.7559) (xy -22.8727 2.7559)
			)
			(stroke
				(width 0)
				(type default)
			)
			(fill no)
			(layer "F.CrtYd")
		)
		(fp_poly
			(pts
				(xy 1.397 4.5466) (xy 1.397 3.2639) (xy -23.6728 3.2639) (xy -23.6728 -3.5052) (xy 23.6728 -3.5052)
				(xy 23.6728 -0.00635) (xy 22.8727 -0.00635) (xy 22.8727 -2.7559) (xy -22.8727 -2.7559) (xy -22.8727 2.7559)
				(xy 1.905 2.7559) (xy 1.905 3.5179) (xy 8.255 3.5179) (xy 8.255 2.7559) (xy 22.8727 2.7559) (xy 22.8727 0.00635)
				(xy 23.6728 0.00635) (xy 23.6728 3.2639) (xy 8.763 3.2639) (xy 8.763 4.5466)
			)
			(stroke
				(width 0)
				(type default)
			)
			(fill no)
			(layer "F.CrtYd")
		)
		(fp_poly
			(pts
				(xy 1.397 4.5466) (xy 1.397 3.2639) (xy -23.6728 3.2639) (xy -23.6728 -3.5052) (xy 23.6728 -3.5052)
				(xy 23.6728 3.2639) (xy 8.763 3.2639) (xy 8.763 4.5466)
			)
			(stroke
				(width 0)
				(type default)
			)
			(fill no)
			(layer "F.Fab")
		)
		(pad "" np_thru_hole circle
			(at -18.874994 0 270)
			(size 0.254 0.254)
			(drill 1.3462)
			(layers "*.Cu" "*.Mask")
			(clearance 0.9017)
			(thermal_gap 0.9017)
		)
		(pad "" np_thru_hole circle
			(at 18.874994 0 270)
			(size 0.254 0.254)
			(drill 0.9398)
			(layers "*.Cu" "*.Mask")
			(clearance 0.6985)
			(thermal_gap 0.6985)
		)
		(pad "G1" smd rect
			(at 21.874988 0 270)
			(size 2.5908 2.5908)
			(layers "F.Cu" "F.Mask" "F.Paste")
			(net "GND")
		)
		(pad "G2" smd rect
			(at -21.874988 0 270)
			(size 2.5908 2.5908)
			(layers "F.Cu" "F.Mask" "F.Paste")
			(net "GND")
		)
		(pad "P1" smd rect
			(at 1.905 -1.82499 270)
			(size 0.6096 2.3622)
			(layers "F.Cu" "F.Mask" "F.Paste")
			(net "Net_2056")
		)
		(pad "P2" smd rect
			(at 0.635 -1.82499 270)
			(size 0.6096 2.3622)
			(layers "F.Cu" "F.Mask" "F.Paste")
			(net "Net_2057")
		)
		(pad "P3" smd rect
			(at -0.635 -1.82499 270)
			(size 0.6096 2.3622)
			(layers "F.Cu" "F.Mask" "F.Paste")
			(net "Net_2058")
		)
		(pad "P4" smd rect
			(at -1.905 -1.82499 270)
			(size 0.6096 2.3622)
			(layers "F.Cu" "F.Mask" "F.Paste")
			(net "GND")
		)
		(pad "P5" smd rect
			(at -3.175 -1.82499 270)
			(size 0.6096 2.3622)
			(layers "F.Cu" "F.Mask" "F.Paste")
			(net "HDD_PRSNT_30")
		)
		(pad "P6" smd rect
			(at -4.445 -1.82499 270)
			(size 0.6096 2.3622)
			(layers "F.Cu" "F.Mask" "F.Paste")
			(net "GND")
		)
		(pad "P7" smd rect
			(at -5.715 -1.82499 270)
			(size 0.6096 2.3622)
			(layers "F.Cu" "F.Mask" "F.Paste")
			(net "5V_PRE_30")
		)
		(pad "P8" smd rect
			(at -6.985 -1.82499 270)
			(size 0.6096 2.3622)
			(layers "F.Cu" "F.Mask" "F.Paste")
			(net "P5V_HDD30")
		)
		(pad "P9" smd rect
			(at -8.255 -1.82499 270)
			(size 0.6096 2.3622)
			(layers "F.Cu" "F.Mask" "F.Paste")
			(net "P5V_HDD30")
		)
		(pad "P10" smd rect
			(at -9.525 -1.82499 270)
			(size 0.6096 2.3622)
			(layers "F.Cu" "F.Mask" "F.Paste")
			(net "GND")
		)
		(pad "P11" smd rect
			(at -10.795 -1.82499 270)
			(size 0.6096 2.3622)
			(layers "F.Cu" "F.Mask" "F.Paste")
			(net "ACT_HDD_30")
		)
		(pad "P12" smd rect
			(at -12.065 -1.82499 270)
			(size 0.6096 2.3622)
			(layers "F.Cu" "F.Mask" "F.Paste")
			(net "GND")
		)
		(pad "P13" smd rect
			(at -13.335 -1.82499 270)
			(size 0.6096 2.3622)
			(layers "F.Cu" "F.Mask" "F.Paste")
			(net "12V_PRE_30")
		)
		(pad "P14" smd rect
			(at -14.605 -1.82499 270)
			(size 0.6096 2.3622)
			(layers "F.Cu" "F.Mask" "F.Paste")
			(net "P12V_HDD30")
		)
		(pad "P15" smd rect
			(at -15.875 -1.82499 270)
			(size 0.6096 2.3622)
			(layers "F.Cu" "F.Mask" "F.Paste")
			(net "P12V_HDD30")
		)
		(pad "S1" smd rect
			(at 15.875 -1.82499 270)
			(size 0.6096 2.3622)
			(layers "F.Cu" "F.Mask" "F.Paste")
			(net "GND")
		)
		(pad "S2" smd rect
			(at 14.605 -1.82499 270)
			(size 0.6096 2.3622)
			(layers "F.Cu" "F.Mask" "F.Paste")
			(net "SAS_HDD_RX_P30")
		)
		(pad "S3" smd rect
			(at 13.335 -1.82499 270)
			(size 0.6096 2.3622)
			(layers "F.Cu" "F.Mask" "F.Paste")
			(net "SAS_HDD_RX_N30")
		)
		(pad "S4" smd rect
			(at 12.065 -1.82499 270)
			(size 0.6096 2.3622)
			(layers "F.Cu" "F.Mask" "F.Paste")
			(net "GND")
		)
		(pad "S5" smd rect
			(at 10.795 -1.82499 270)
			(size 0.6096 2.3622)
			(layers "F.Cu" "F.Mask" "F.Paste")
			(net "PHY_DRV_A_TO_SCC_A_30_DN")
		)
		(pad "S6" smd rect
			(at 9.525 -1.82499 270)
			(size 0.6096 2.3622)
			(layers "F.Cu" "F.Mask" "F.Paste")
			(net "PHY_DRV_A_TO_SCC_A_30_DP")
		)
		(pad "S7" smd rect
			(at 8.255 -1.82499 270)
			(size 0.6096 2.3622)
			(layers "F.Cu" "F.Mask" "F.Paste")
			(net "GND")
		)
		(pad "S8" smd rect
			(at 7.480046 2.845054 270)
			(size 0.508 2.3622)
			(layers "F.Cu" "F.Mask" "F.Paste")
			(net "GND")
		)
		(pad "S9" smd rect
			(at 6.679946 2.845054 270)
			(size 0.508 2.3622)
			(layers "F.Cu" "F.Mask" "F.Paste")
			(net "Net_469")
		)
		(pad "S10" smd rect
			(at 5.8801 2.845054 270)
			(size 0.508 2.3622)
			(layers "F.Cu" "F.Mask" "F.Paste")
			(net "Net_361")
		)
		(pad "S11" smd rect
			(at 5.08 2.845054 270)
			(size 0.508 2.3622)
			(layers "F.Cu" "F.Mask" "F.Paste")
			(net "GND")
		)
		(pad "S12" smd rect
			(at 4.2799 2.845054 270)
			(size 0.508 2.3622)
			(layers "F.Cu" "F.Mask" "F.Paste")
			(net "Net_397")
		)
		(pad "S13" smd rect
			(at 3.480054 2.845054 270)
			(size 0.508 2.3622)
			(layers "F.Cu" "F.Mask" "F.Paste")
			(net "Net_433")
		)
		(pad "S14" smd rect
			(at 2.679954 2.845054 270)
			(size 0.508 2.3622)
			(layers "F.Cu" "F.Mask" "F.Paste")
			(net "GND")
		)
		(zone
			(layer "F.Cu")
			(hatch none 0.5)
			(connect_pads
				(clearance 0)
			)
			(min_thickness 0.25)
			(keepout
				(tracks allowed)
				(vias not_allowed)
				(pads allowed)
				(copperpour not_allowed)
				(footprints allowed)
			)
			(placement
				(enabled no)
				(sheetname "")
			)
			(fill
				(thermal_gap 0.5)
				(thermal_bridge_width 0.5)
				(island_removal_mode 0)
			)
			(polygon
				(pts
					(xy 329.207622 -74.648568) (xy 322.133722 -74.648568) (xy 322.133722 -81.582768) (xy 323.238622 -81.582768)
					(xy 323.238622 -77.467968) (xy 327.861422 -77.467968) (xy 327.861422 -81.582768) (xy 329.207622 -81.582768)
				)
			)
		)
		(zone
			(layer "F.Cu")
			(hatch none 0.5)
			(connect_pads
				(clearance 0)
			)
			(min_thickness 0.25)
			(keepout
				(tracks not_allowed)
				(vias allowed)
				(pads allowed)
				(copperpour not_allowed)
				(footprints allowed)
			)
			(placement
				(enabled no)
				(sheetname "")
			)
			(fill
				(thermal_gap 0.5)
				(thermal_bridge_width 0.5)
				(island_removal_mode 0)
			)
			(polygon
				(pts
					(xy 329.207622 -74.648568) (xy 322.133722 -74.648568) (xy 322.133722 -81.582768) (xy 323.238622 -81.582768)
					(xy 323.238622 -77.467968) (xy 327.861422 -77.467968) (xy 327.861422 -81.582768) (xy 329.207622 -81.582768)
				)
			)
		)
		(zone
			(layer "F.Cu")
			(hatch none 0.5)
			(connect_pads
				(clearance 0)
			)
			(min_thickness 0.25)
			(keepout
				(tracks allowed)
				(vias not_allowed)
				(pads allowed)
				(copperpour not_allowed)
				(footprints allowed)
			)
			(placement
				(enabled no)
				(sheetname "")
			)
			(fill
				(thermal_gap 0.5)
				(thermal_bridge_width 0.5)
				(island_removal_mode 0)
			)
			(polygon
				(pts
					(xy 329.207622 -41.171368) (xy 322.133722 -41.171368) (xy 322.133722 -34.237168) (xy 323.238622 -34.237168)
					(xy 323.238622 -38.351968) (xy 327.861422 -38.351968) (xy 327.861422 -34.237168) (xy 329.207622 -34.237168)
				)
			)
		)
		(zone
			(layer "F.Cu")
			(hatch none 0.5)
			(connect_pads
				(clearance 0)
			)
			(min_thickness 0.25)
			(keepout
				(tracks not_allowed)
				(vias allowed)
				(pads allowed)
				(copperpour not_allowed)
				(footprints allowed)
			)
			(placement
				(enabled no)
				(sheetname "")
			)
			(fill
				(thermal_gap 0.5)
				(thermal_bridge_width 0.5)
				(island_removal_mode 0)
			)
			(polygon
				(pts
					(xy 329.207622 -41.171368) (xy 322.133722 -41.171368) (xy 322.133722 -34.237168) (xy 323.238622 -34.237168)
					(xy 323.238622 -38.351968) (xy 327.861422 -38.351968) (xy 327.861422 -34.237168) (xy 329.207622 -34.237168)
				)
			)
		)
		(zone
			(layers "F.Cu" "B.Cu" "In1.Cu" "In2.Cu" "In3.Cu" "In4.Cu" "In5.Cu" "In6.Cu"
				"In7.Cu" "In8.Cu" "In9.Cu" "In10.Cu"
			)
			(hatch none 0.5)
			(connect_pads
				(clearance 0)
			)
			(min_thickness 0.25)
			(keepout
				(tracks not_allowed)
				(vias allowed)
				(pads allowed)
				(copperpour not_allowed)
				(footprints allowed)
			)
			(placement
				(enabled no)
				(sheetname "")
			)
			(fill
				(thermal_gap 0.5)
				(thermal_bridge_width 0.5)
				(island_removal_mode 0)
			)
			(polygon
				(pts
					(arc
						(start 326.324722 -39.034974)
						(mid 324.775322 -39.034974)
						(end 326.324722 -39.034974)
					)
				)
			)
		)
		(zone
			(layers "F.Cu" "B.Cu" "In1.Cu" "In2.Cu" "In3.Cu" "In4.Cu" "In5.Cu" "In6.Cu"
				"In7.Cu" "In8.Cu" "In9.Cu" "In10.Cu"
			)
			(hatch none 0.5)
			(connect_pads
				(clearance 0)
			)
			(min_thickness 0.25)
			(keepout
				(tracks not_allowed)
				(vias allowed)
				(pads allowed)
				(copperpour not_allowed)
				(footprints allowed)
			)
			(placement
				(enabled no)
				(sheetname "")
			)
			(fill
				(thermal_gap 0.5)
				(thermal_bridge_width 0.5)
				(island_removal_mode 0)
			)
			(polygon
				(pts
					(arc
						(start 326.527922 -76.784962)
						(mid 324.572122 -76.784962)
						(end 326.527922 -76.784962)
					)
				)
			)
		)
	)
)
